(kicad_pcb
	(version 20260206)
	(generator "pcbnew")
	(generator_version "10.0")
	(general
		(thickness 1.6)
		(legacy_teardrops no)
	)
	(paper "A4")
	(title_block
		(title "04192023_DAF0TMB3IC0_F0TG_MB_C_brd_V02_OCP.brd")
		(comment 1 "Grand Teton / footprints 417-421 of 8354")
	)
	(layers
		(0 "F.Cu" signal "TOP")
		(4 "In1.Cu" signal "GND")
		(6 "In2.Cu" signal "IN1")
		(8 "In3.Cu" signal "GND1")
		(10 "In4.Cu" signal "IN2")
		(12 "In5.Cu" signal "GND2")
		(14 "In6.Cu" signal "IN3")
		(16 "In7.Cu" signal "GND3")
		(18 "In8.Cu" signal "VCC")
		(20 "In9.Cu" signal "VCC1")
		(22 "In10.Cu" signal "GND4")
		(24 "In11.Cu" signal "IN4")
		(26 "In12.Cu" signal "GND5")
		(28 "In13.Cu" signal "IN5")
		(30 "In14.Cu" signal "GND6")
		(32 "In15.Cu" signal "IN6")
		(34 "In16.Cu" signal "GND7")
		(2 "B.Cu" signal "BOTTOM")
		(9 "F.Adhes" user "F.Adhesive")
		(11 "B.Adhes" user "B.Adhesive")
		(13 "F.Paste" user "Package Geometry/Pastemask Top")
		(15 "B.Paste" user "Package Geometry/Pastemask Bottom")
		(5 "F.SilkS" user "Ref Des/Silkscreen Top")
		(7 "B.SilkS" user "Ref Des/Silkscreen Bottom")
		(1 "F.Mask" user "Board Geometry/Soldermask Top")
		(3 "B.Mask" user "Board Geometry/Soldermask Bottom")
		(17 "Dwgs.User" user "User.Drawings")
		(19 "Cmts.User" user "User.Comments")
		(21 "Eco1.User" user "User.Eco1")
		(23 "Eco2.User" user "User.Eco2")
		(25 "Edge.Cuts" user "Board Geometry/Outline")
		(27 "Margin" user)
		(31 "F.CrtYd" user "Package Geometry/Place Bound Top")
		(29 "B.CrtYd" user "Package Geometry/Place Bound Bottom")
		(35 "F.Fab" user "Ref Des/Assembly Top")
		(33 "B.Fab" user "Ref Des/Assembly Bottom")
	)
	(footprint ""
		(layer "F.Cu")
		(at 112.649 -123.952 90)
		(property "Reference" "R1491"
			(at 0 0 90)
			(layer "F.SilkS")
			(hide yes)
			(effects
				(font
					(size 1.27 1.27)
				)
			)
		)
		(property "Value" ""
			(at 0 0 90)
			(layer "F.Fab")
			(effects
				(font
					(size 1.27 1.27)
				)
			)
		)
		(duplicate_pad_numbers_are_jumpers no)
		(fp_line
			(start 0.7874 -0.4064)
			(end 0.7874 0.4064)
			(stroke
				(width 0.1524)
				(type default)
			)
			(layer "F.SilkS")
		)
		(fp_line
			(start -0.7874 -0.4064)
			(end 0.7874 -0.4064)
			(stroke
				(width 0.1524)
				(type default)
			)
			(layer "F.SilkS")
		)
		(fp_line
			(start 0.7874 0.4064)
			(end -0.7874 0.4064)
			(stroke
				(width 0.1524)
				(type default)
			)
			(layer "F.SilkS")
		)
		(fp_line
			(start -0.7874 0.4064)
			(end -0.7874 -0.4064)
			(stroke
				(width 0.1524)
				(type default)
			)
			(layer "F.SilkS")
		)
		(fp_line
			(start -0.12065 -0.305054)
			(end -0.12065 -0.2794)
			(stroke
				(width 0.1)
				(type default)
			)
			(layer "F.Fab")
		)
		(fp_line
			(start -0.67945 -0.305054)
			(end -0.12065 -0.305054)
			(stroke
				(width 0.1)
				(type default)
			)
			(layer "F.Fab")
		)
		(fp_line
			(start 0.67945 -0.3048)
			(end 0.67945 0.3048)
			(stroke
				(width 0.1)
				(type default)
			)
			(layer "F.Fab")
		)
		(fp_line
			(start 0.12065 -0.3048)
			(end 0.67945 -0.3048)
			(stroke
				(width 0.1)
				(type default)
			)
			(layer "F.Fab")
		)
		(fp_line
			(start 0.12065 -0.2794)
			(end 0.12065 -0.3048)
			(stroke
				(width 0.1)
				(type default)
			)
			(layer "F.Fab")
		)
		(fp_line
			(start -0.12065 -0.2794)
			(end 0.12065 -0.2794)
			(stroke
				(width 0.1)
				(type default)
			)
			(layer "F.Fab")
		)
		(fp_line
			(start 0.120396 0.2794)
			(end -0.12065 0.2794)
			(stroke
				(width 0.1)
				(type default)
			)
			(layer "F.Fab")
		)
		(fp_line
			(start -0.12065 0.2794)
			(end -0.12065 0.3048)
			(stroke
				(width 0.1)
				(type default)
			)
			(layer "F.Fab")
		)
		(fp_line
			(start 0.67945 0.3048)
			(end 0.120396 0.3048)
			(stroke
				(width 0.1)
				(type default)
			)
			(layer "F.Fab")
		)
		(fp_line
			(start 0.120396 0.3048)
			(end 0.120396 0.2794)
			(stroke
				(width 0.1)
				(type default)
			)
			(layer "F.Fab")
		)
		(fp_line
			(start -0.12065 0.3048)
			(end -0.67945 0.3048)
			(stroke
				(width 0.1)
				(type default)
			)
			(layer "F.Fab")
		)
		(fp_line
			(start -0.67945 0.3048)
			(end -0.67945 -0.305054)
			(stroke
				(width 0.1)
				(type default)
			)
			(layer "F.Fab")
		)
		(pad "1" smd circle
			(at -0.40005 0 90)
			(size 0 0)
			(layers "F.Cu" "F.Mask" "F.Paste")
			(net "P3V3")
		)
		(pad "2" smd circle
			(at 0.40005 0 90)
			(size 0 0)
			(layers "F.Cu" "F.Mask" "F.Paste")
			(net "PWRGD_P3V3_EN_R")
		)
	)
	(footprint ""
		(layer "F.Cu")
		(at 268.645386 -51.999896)
		(property "Reference" "H114"
			(at -8.10006 -6.85419 0)
			(unlocked yes)
			(layer "F.SilkS")
			(effects
				(font
					(size 0.7874 0.5842)
					(thickness 0.1524)
				)
				(justify left)
			)
		)
		(property "Value" ""
			(at 0 0 0)
			(layer "F.Fab")
			(effects
				(font
					(size 1.27 1.27)
				)
			)
		)
		(duplicate_pad_numbers_are_jumpers no)
		(fp_circle
			(center 0 0)
			(end 7.999984 0)
			(stroke
				(width 0.1524)
				(type default)
			)
			(fill no)
			(layer "F.SilkS")
		)
		(fp_circle
			(center 0 0)
			(end 7.999984 0)
			(stroke
				(width 0.1524)
				(type default)
			)
			(fill no)
			(layer "B.SilkS")
		)
		(fp_circle
			(center 0 0)
			(end 7.999984 0)
			(stroke
				(width 0.1)
				(type default)
			)
			(fill no)
			(layer "B.Fab")
		)
		(fp_circle
			(center 0 0)
			(end 7.999984 0)
			(stroke
				(width 0.1)
				(type default)
			)
			(fill no)
			(layer "F.Fab")
		)
		(pad "" np_thru_hole circle
			(at 0 0)
			(size 5.5118 5.5118)
			(drill 5.5118)
			(layers "*.Cu" "*.Mask")
			(clearance 0.381)
			(thermal_gap 0.381)
		)
		(pad "2" thru_hole circle
			(at 0 -3.999992)
			(size 0.762 0.762)
			(drill 0.5588)
			(layers "*.Cu" "*.Mask")
			(remove_unused_layers no)
			(net "GND")
			(clearance 0.1524)
			(thermal_gap 0.1524)
		)
		(pad "3" thru_hole circle
			(at -2.999994 -2.500122)
			(size 0.762 0.762)
			(drill 0.5588)
			(layers "*.Cu" "*.Mask")
			(remove_unused_layers no)
			(net "GND")
			(clearance 0.1524)
			(thermal_gap 0.1524)
		)
		(pad "4" thru_hole circle
			(at -3.999992 0)
			(size 0.762 0.762)
			(drill 0.5588)
			(layers "*.Cu" "*.Mask")
			(remove_unused_layers no)
			(net "GND")
			(clearance 0.1524)
			(thermal_gap 0.1524)
		)
		(pad "5" thru_hole circle
			(at -2.999994 2.500122)
			(size 0.762 0.762)
			(drill 0.5588)
			(layers "*.Cu" "*.Mask")
			(remove_unused_layers no)
			(net "GND")
			(clearance 0.1524)
			(thermal_gap 0.1524)
		)
		(pad "6" thru_hole circle
			(at 0 3.999992)
			(size 0.762 0.762)
			(drill 0.5588)
			(layers "*.Cu" "*.Mask")
			(remove_unused_layers no)
			(net "GND")
			(clearance 0.1524)
			(thermal_gap 0.1524)
		)
		(pad "7" thru_hole circle
			(at 2.999994 2.500122)
			(size 0.762 0.762)
			(drill 0.5588)
			(layers "*.Cu" "*.Mask")
			(remove_unused_layers no)
			(net "GND")
			(clearance 0.1524)
			(thermal_gap 0.1524)
		)
		(pad "8" thru_hole circle
			(at 3.999992 0)
			(size 0.762 0.762)
			(drill 0.5588)
			(layers "*.Cu" "*.Mask")
			(remove_unused_layers no)
			(net "GND")
			(clearance 0.1524)
			(thermal_gap 0.1524)
		)
		(pad "9" thru_hole circle
			(at 2.999994 -2.500122)
			(size 0.762 0.762)
			(drill 0.5588)
			(layers "*.Cu" "*.Mask")
			(remove_unused_layers no)
			(net "GND")
			(clearance 0.1524)
			(thermal_gap 0.1524)
		)
		(zone
			(layer "F.Cu")
			(hatch none 0.5)
			(connect_pads
				(clearance 0)
			)
			(min_thickness 0.25)
			(keepout
				(tracks not_allowed)
				(vias allowed)
				(pads allowed)
				(copperpour not_allowed)
				(footprints allowed)
			)
			(placement
				(enabled no)
				(sheetname "")
			)
			(fill
				(thermal_gap 0.5)
				(thermal_bridge_width 0.5)
				(island_removal_mode 0)
			)
			(polygon
				(pts
					(arc
						(start 268.645386 -59.99988)
						(mid 262.988543 -57.656739)
						(end 260.645402 -51.999896)
					)
					(arc
						(start 260.645402 -51.999896)
						(mid 262.988543 -46.343053)
						(end 268.645386 -43.999912)
					)
					(xy 268.645386 -46.74616) (xy 268.594332 -46.74616)
					(arc
						(start 268.594078 -46.74616)
						(mid 263.391399 -51.999896)
						(end 268.594078 -57.253632)
					)
					(xy 268.594332 -57.253632) (xy 268.645386 -57.253632)
				)
			)
		)
		(zone
			(layer "F.Cu")
			(hatch none 0.5)
			(connect_pads
				(clearance 0)
			)
			(min_thickness 0.25)
			(keepout
				(tracks not_allowed)
				(vias allowed)
				(pads allowed)
				(copperpour not_allowed)
				(footprints allowed)
			)
			(placement
				(enabled no)
				(sheetname "")
			)
			(fill
				(thermal_gap 0.5)
				(thermal_bridge_width 0.5)
				(island_removal_mode 0)
			)
			(polygon
				(pts
					(arc
						(start 268.645386 -59.99988)
						(mid 274.302229 -57.656739)
						(end 276.64537 -51.999896)
					)
					(arc
						(start 276.64537 -51.999896)
						(mid 274.302229 -46.343053)
						(end 268.645386 -43.999912)
					)
					(xy 268.645386 -46.74616) (xy 268.69644 -46.74616)
					(arc
						(start 268.696694 -46.74616)
						(mid 273.899373 -51.999896)
						(end 268.696694 -57.253632)
					)
					(xy 268.69644 -57.253632) (xy 268.645386 -57.253632)
				)
			)
		)
		(zone
			(layers "F.Cu" "B.Cu" "In1.Cu" "In2.Cu" "In3.Cu" "In4.Cu" "In5.Cu" "In6.Cu"
				"In7.Cu" "In8.Cu" "In9.Cu" "In10.Cu" "In11.Cu" "In12.Cu" "In13.Cu" "In14.Cu"
				"In15.Cu" "In16.Cu"
			)
			(hatch none 0.5)
			(connect_pads
				(clearance 0)
			)
			(min_thickness 0.25)
			(keepout
				(tracks not_allowed)
				(vias allowed)
				(pads allowed)
				(copperpour not_allowed)
				(footprints allowed)
			)
			(placement
				(enabled no)
				(sheetname "")
			)
			(fill
				(thermal_gap 0.5)
				(thermal_bridge_width 0.5)
				(island_removal_mode 0)
			)
			(polygon
				(pts
					(arc
						(start 271.921986 -51.999896)
						(mid 265.368786 -51.999896)
						(end 271.921986 -51.999896)
					)
				)
			)
		)
		(zone
			(layer "B.Cu")
			(hatch none 0.5)
			(connect_pads
				(clearance 0)
			)
			(min_thickness 0.25)
			(keepout
				(tracks not_allowed)
				(vias allowed)
				(pads allowed)
				(copperpour not_allowed)
				(footprints allowed)
			)
			(placement
				(enabled no)
				(sheetname "")
			)
			(fill
				(thermal_gap 0.5)
				(thermal_bridge_width 0.5)
				(island_removal_mode 0)
			)
			(polygon
				(pts
					(arc
						(start 268.645386 -57.507886)
						(mid 263.137396 -51.999896)
						(end 268.645386 -46.491906)
					)
					(arc
						(start 268.645386 -46.974506)
						(mid 263.619996 -51.999896)
						(end 268.645386 -57.025286)
					)
				)
			)
		)
		(zone
			(layer "B.Cu")
			(hatch none 0.5)
			(connect_pads
				(clearance 0)
			)
			(min_thickness 0.25)
			(keepout
				(tracks not_allowed)
				(vias allowed)
				(pads allowed)
				(copperpour not_allowed)
				(footprints allowed)
			)
			(placement
				(enabled no)
				(sheetname "")
			)
			(fill
				(thermal_gap 0.5)
				(thermal_bridge_width 0.5)
				(island_removal_mode 0)
			)
			(polygon
				(pts
					(arc
						(start 268.645386 -57.507886)
						(mid 274.153376 -51.999896)
						(end 268.645386 -46.491906)
					)
					(arc
						(start 268.645386 -46.974506)
						(mid 273.670776 -51.999896)
						(end 268.645386 -57.025286)
					)
				)
			)
		)
	)
	(footprint ""
		(layer "F.Cu")
		(at 41.741852 -383.7432)
		(property "Reference" "R724"
			(at 0 0 0)
			(layer "F.SilkS")
			(hide yes)
			(effects
				(font
					(size 1.27 1.27)
				)
			)
		)
		(property "Value" ""
			(at 0 0 0)
			(layer "F.Fab")
			(effects
				(font
					(size 1.27 1.27)
				)
			)
		)
		(duplicate_pad_numbers_are_jumpers no)
		(fp_line
			(start -0.32512 -0.175006)
			(end 0.32512 -0.175006)
			(stroke
				(width 0.1)
				(type default)
			)
			(layer "F.Fab")
		)
		(fp_line
			(start -0.32512 0.175006)
			(end -0.32512 -0.175006)
			(stroke
				(width 0.1)
				(type default)
			)
			(layer "F.Fab")
		)
		(fp_line
			(start 0.32512 -0.175006)
			(end 0.32512 0.175006)
			(stroke
				(width 0.1)
				(type default)
			)
			(layer "F.Fab")
		)
		(fp_line
			(start 0.32512 0.175006)
			(end -0.32512 0.175006)
			(stroke
				(width 0.1)
				(type default)
			)
			(layer "F.Fab")
		)
		(pad "1" smd rect
			(at -0.2667 0)
			(size 0.3048 0.381)
			(layers "F.Cu" "F.Mask" "F.Paste")
			(net "P1V8_CPU1_RT_1D")
		)
		(pad "2" smd rect
			(at 0.2667 0 180)
			(size 0.3048 0.381)
			(layers "F.Cu" "F.Mask" "F.Paste")
			(net "TEST2_RT_CPU1_P0")
		)
	)
	(footprint ""
		(layer "F.Cu")
		(at 329.877928 -137.575036 180)
		(property "Reference" "C674"
			(at 0 0 180)
			(layer "F.SilkS")
			(hide yes)
			(effects
				(font
					(size 1.27 1.27)
				)
			)
		)
		(property "Value" ""
			(at 0 0 180)
			(layer "F.Fab")
			(effects
				(font
					(size 1.27 1.27)
				)
			)
		)
		(duplicate_pad_numbers_are_jumpers no)
		(fp_line
			(start 0.7874 0.4064)
			(end -0.7874 0.4064)
			(stroke
				(width 0.1524)
				(type default)
			)
			(layer "F.SilkS")
		)
		(fp_line
			(start 0.7874 -0.4064)
			(end 0.7874 0.4064)
			(stroke
				(width 0.1524)
				(type default)
			)
			(layer "F.SilkS")
		)
		(fp_line
			(start -0.7874 0.4064)
			(end -0.7874 -0.4064)
			(stroke
				(width 0.1524)
				(type default)
			)
			(layer "F.SilkS")
		)
		(fp_line
			(start -0.7874 -0.4064)
			(end 0.7874 -0.4064)
			(stroke
				(width 0.1524)
				(type default)
			)
			(layer "F.SilkS")
		)
		(fp_line
			(start 0.67945 0.3048)
			(end 0.120396 0.3048)
			(stroke
				(width 0.1)
				(type default)
			)
			(layer "F.Fab")
		)
		(fp_line
			(start 0.67945 -0.3048)
			(end 0.67945 0.3048)
			(stroke
				(width 0.1)
				(type default)
			)
			(layer "F.Fab")
		)
		(fp_line
			(start 0.12065 -0.2794)
			(end 0.12065 -0.3048)
			(stroke
				(width 0.1)
				(type default)
			)
			(layer "F.Fab")
		)
		(fp_line
			(start 0.12065 -0.3048)
			(end 0.67945 -0.3048)
			(stroke
				(width 0.1)
				(type default)
			)
			(layer "F.Fab")
		)
		(fp_line
			(start 0.120396 0.3048)
			(end 0.120396 0.2794)
			(stroke
				(width 0.1)
				(type default)
			)
			(layer "F.Fab")
		)
		(fp_line
			(start 0.120396 0.2794)
			(end -0.12065 0.2794)
			(stroke
				(width 0.1)
				(type default)
			)
			(layer "F.Fab")
		)
		(fp_line
			(start -0.12065 0.3048)
			(end -0.67945 0.3048)
			(stroke
				(width 0.1)
				(type default)
			)
			(layer "F.Fab")
		)
		(fp_line
			(start -0.12065 0.2794)
			(end -0.12065 0.3048)
			(stroke
				(width 0.1)
				(type default)
			)
			(layer "F.Fab")
		)
		(fp_line
			(start -0.12065 -0.2794)
			(end 0.12065 -0.2794)
			(stroke
				(width 0.1)
				(type default)
			)
			(layer "F.Fab")
		)
		(fp_line
			(start -0.12065 -0.305054)
			(end -0.12065 -0.2794)
			(stroke
				(width 0.1)
				(type default)
			)
			(layer "F.Fab")
		)
		(fp_line
			(start -0.67945 0.3048)
			(end -0.67945 -0.305054)
			(stroke
				(width 0.1)
				(type default)
			)
			(layer "F.Fab")
		)
		(fp_line
			(start -0.67945 -0.305054)
			(end -0.12065 -0.305054)
			(stroke
				(width 0.1)
				(type default)
			)
			(layer "F.Fab")
		)
		(pad "1" smd circle
			(at -0.40005 0 180)
			(size 0 0)
			(layers "F.Cu" "F.Mask" "F.Paste")
			(net "PVDD18_S5_P0_EN")
		)
		(pad "2" smd circle
			(at 0.40005 0 180)
			(size 0 0)
			(layers "F.Cu" "F.Mask" "F.Paste")
			(net "GND")
		)
	)
	(footprint ""
		(layer "F.Cu")
		(at 37.40658 -116.23802 90)
		(property "Reference" "Q7001"
			(at -2.4384 -3.292348 90)
			(unlocked yes)
			(layer "F.SilkS")
			(effects
				(font
					(size 0.7874 0.5842)
					(thickness 0.1524)
				)
				(justify left)
			)
		)
		(property "Value" ""
			(at 0 0 90)
			(layer "F.Fab")
			(effects
				(font
					(size 1.27 1.27)
				)
			)
		)
		(duplicate_pad_numbers_are_jumpers no)
		(fp_line
			(start 2.350008 -2.649982)
			(end 2.350008 -2.4892)
			(stroke
				(width 0.1524)
				(type default)
			)
			(layer "F.SilkS")
		)
		(fp_line
			(start -2.350008 -2.649982)
			(end 2.350008 -2.649982)
			(stroke
				(width 0.1524)
				(type default)
			)
			(layer "F.SilkS")
		)
		(fp_line
			(start -2.350008 -2.4384)
			(end -2.350008 -2.649982)
			(stroke
				(width 0.1524)
				(type default)
			)
			(layer "F.SilkS")
		)
		(fp_line
			(start 2.350008 2.4892)
			(end 2.350008 2.649982)
			(stroke
				(width 0.1524)
				(type default)
			)
			(layer "F.SilkS")
		)
		(fp_line
			(start 2.350008 2.649982)
			(end -2.350008 2.649982)
			(stroke
				(width 0.1524)
				(type default)
			)
			(layer "F.SilkS")
		)
		(fp_line
			(start -2.350008 2.649982)
			(end -2.350008 2.413)
			(stroke
				(width 0.1524)
				(type default)
			)
			(layer "F.SilkS")
		)
		(fp_poly
			(pts
				(xy -3.717544 -1.905) (xy -4.758944 -2.3241) (xy -4.758944 -1.524)
			)
			(stroke
				(width 0)
				(type default)
			)
			(fill yes)
			(layer "F.SilkS")
		)
		(fp_line
			(start 2.350008 -2.649982)
			(end 2.350008 2.649982)
			(stroke
				(width 0.1)
				(type default)
			)
			(layer "F.Fab")
		)
		(fp_line
			(start -2.350008 -2.649982)
			(end 2.350008 -2.649982)
			(stroke
				(width 0.1)
				(type default)
			)
			(layer "F.Fab")
		)
		(fp_line
			(start 2.350008 2.649982)
			(end -2.350008 2.649982)
			(stroke
				(width 0.1)
				(type default)
			)
			(layer "F.Fab")
		)
		(fp_line
			(start -2.350008 2.649982)
			(end -2.350008 -2.649982)
			(stroke
				(width 0.1)
				(type default)
			)
			(layer "F.Fab")
		)
		(fp_poly
			(pts
				(xy -3.717544 -1.905) (xy -4.758944 -2.3241) (xy -4.758944 -1.524)
			)
			(stroke
				(width 0)
				(type default)
			)
			(fill yes)
			(layer "F.Fab")
		)
		(pad "1" smd rect
			(at -2.999994 -1.905)
			(size 0.7112 1.1684)
			(layers "F.Cu" "F.Mask" "F.Paste")
			(net "GND")
		)
		(pad "2" smd rect
			(at -2.999994 -0.635)
			(size 0.7112 1.1684)
			(layers "F.Cu" "F.Mask" "F.Paste")
			(net "GND")
		)
		(pad "3" smd rect
			(at -2.999994 0.635)
			(size 0.7112 1.1684)
			(layers "F.Cu" "F.Mask" "F.Paste")
			(net "GND")
		)
		(pad "4" smd rect
			(at -2.999994 1.905)
			(size 0.7112 1.1684)
			(layers "F.Cu" "F.Mask" "F.Paste")
			(net "P12V_AUX_DSC_G2")
		)
		(pad "5" smd circle
			(at 0.925068 0)
			(size 0 0)
			(layers "F.Cu" "F.Mask" "F.Paste")
			(net "P12V_AUX_DSC")
		)
		(zone
			(layer "F.Cu")
			(hatch none 0.5)
			(connect_pads
				(clearance 0)
			)
			(min_thickness 0.25)
			(keepout
				(tracks not_allowed)
				(vias allowed)
				(pads allowed)
				(copperpour not_allowed)
				(footprints allowed)
			)
			(placement
				(enabled no)
				(sheetname "")
			)
			(fill
				(thermal_gap 0.5)
				(thermal_bridge_width 0.5)
				(island_removal_mode 0)
			)
			(polygon
				(pts
					(xy 34.76498 -118.57482) (xy 34.99358 -118.57482) (xy 34.99358 -117.88902) (xy 35.24758 -117.88902)
					(xy 35.24758 -114.79022) (xy 39.56558 -114.79022) (xy 39.56558 -117.88902) (xy 39.81958 -117.88902)
					(xy 39.81958 -118.57482) (xy 40.04818 -118.57482) (xy 40.04818 -113.88852) (xy 34.76498 -113.88852)
				)
			)
		)
	)
)
